# BASEBOARD_FAB2 (Tioga Pass) — schematic netlist excerpt (pin names and nets, part order shuffled) for the footprints in the layout excerpt that follows; sources: Cadence DE-HDL packaged netlist, KiCad conversion of Wiwynn_Tioga_Pass_MB.brd

R25W29  120R2F-GP  1%  pkg RCL_GP  page 151 : \1\ = BMC_M_RST_N ; \2\ = P1V2_AUX_BMC
T1P35  TPAD-SE-2P-GP  pkg DISCRET-GA1  page 256 : \1\ = L12_50OHM_6INCH ; GND1 = GND
R8D26  RES  4.75K 1% CHIP  pkg 0402  page 170 : A = P3V3_STBY ; B = IRQ_SML1_PMBUS_ALERT_BUF_N

(kicad_pcb
	(version 20260206)
	(generator "pcbnew")
	(generator_version "10.0")
	(general
		(thickness 1.6)
		(legacy_teardrops no)
	)
	(paper "A4")
	(title_block
		(title "Wiwynn_Tioga_Pass_MB.brd")
		(comment 1 "Tioga Pass / footprints 1516-1518 of 4770")
	)
	(layers
		(0 "F.Cu" signal "TOP")
		(4 "In1.Cu" signal "L2GND")
		(6 "In2.Cu" signal "L3")
		(8 "In3.Cu" signal "L4GND")
		(10 "In4.Cu" signal "L5")
		(12 "In5.Cu" signal "L6GND")
		(14 "In6.Cu" signal "L7VCC")
		(16 "In7.Cu" signal "L8VCC")
		(18 "In8.Cu" signal "L9GND")
		(20 "In9.Cu" signal "L10")
		(22 "In10.Cu" signal "L11GND")
		(24 "In11.Cu" signal "L12")
		(26 "In12.Cu" signal "L13GND")
		(2 "B.Cu" signal "BOTTOM")
		(9 "F.Adhes" user "F.Adhesive")
		(11 "B.Adhes" user "B.Adhesive")
		(13 "F.Paste" user "Package Geometry/Pastemask Top")
		(15 "B.Paste" user "Package Geometry/Pastemask Bottom")
		(5 "F.SilkS" user "Ref Des/Silkscreen Top")
		(7 "B.SilkS" user "Ref Des/Silkscreen Bottom")
		(1 "F.Mask" user "Board Geometry/Soldermask Top")
		(3 "B.Mask" user "Board Geometry/Soldermask Bottom")
		(17 "Dwgs.User" user "User.Drawings")
		(19 "Cmts.User" user "User.Comments")
		(21 "Eco1.User" user "User.Eco1")
		(23 "Eco2.User" user "User.Eco2")
		(25 "Edge.Cuts" user "Board Geometry/Outline")
		(27 "Margin" user)
		(31 "F.CrtYd" user "Package Geometry/Place Bound Top")
		(29 "B.CrtYd" user "Package Geometry/Place Bound Bottom")
		(35 "F.Fab" user "Ref Des/Assembly Top")
		(33 "B.Fab" user "Ref Des/Assembly Bottom")
	)
	(footprint ""
		(layer "F.Cu")
		(at 422.148 -84.3915)
		(property "Reference" "R8D26"
			(at 0 0 0)
			(layer "F.SilkS")
			(hide yes)
			(effects
				(font
					(size 1.27 1.27)
				)
			)
		)
		(property "Value" ""
			(at 0 0 0)
			(layer "F.Fab")
			(effects
				(font
					(size 1.27 1.27)
				)
			)
		)
		(duplicate_pad_numbers_are_jumpers no)
		(fp_poly
			(pts
				(xy -0.2794 -0.1016) (xy 0.2794 -0.1016) (xy 0.2794 0.9906) (xy -0.2794 0.9906)
			)
			(stroke
				(width 0)
				(type default)
			)
			(fill no)
			(layer "F.CrtYd")
		)
		(fp_line
			(start -0.2794 -0.1016)
			(end -0.2794 0.9906)
			(stroke
				(width 0.1)
				(type default)
			)
			(layer "F.Fab")
		)
		(fp_line
			(start -0.2794 0.9906)
			(end 0.2794 0.9906)
			(stroke
				(width 0.1)
				(type default)
			)
			(layer "F.Fab")
		)
		(fp_line
			(start 0.2794 -0.1016)
			(end -0.2794 -0.1016)
			(stroke
				(width 0.1)
				(type default)
			)
			(layer "F.Fab")
		)
		(fp_line
			(start 0.2794 0.9906)
			(end 0.2794 -0.1016)
			(stroke
				(width 0.1)
				(type default)
			)
			(layer "F.Fab")
		)
		(pad "1" smd rect
			(at 0 0)
			(size 0.508 0.508)
			(layers "F.Cu" "F.Mask" "F.Paste")
			(net "P3V3_STBY")
		)
		(pad "2" smd rect
			(at 0 0.889)
			(size 0.508 0.508)
			(layers "F.Cu" "F.Mask" "F.Paste")
			(net "IRQ_SML1_PMBUS_ALERT_BUF_N")
		)
		(zone
			(layer "F.Cu")
			(hatch none 0.5)
			(connect_pads
				(clearance 0)
			)
			(min_thickness 0.25)
			(keepout
				(tracks allowed)
				(vias not_allowed)
				(pads allowed)
				(copperpour not_allowed)
				(footprints allowed)
			)
			(placement
				(enabled no)
				(sheetname "")
			)
			(fill
				(thermal_gap 0.5)
				(thermal_bridge_width 0.5)
				(island_removal_mode 0)
			)
			(polygon
				(pts
					(xy 421.894 -84.1375) (xy 422.402 -84.1375) (xy 422.402 -83.7565) (xy 421.894 -83.7565)
				)
			)
		)
		(zone
			(layer "F.Cu")
			(hatch none 0.5)
			(connect_pads
				(clearance 0)
			)
			(min_thickness 0.25)
			(keepout
				(tracks not_allowed)
				(vias allowed)
				(pads allowed)
				(copperpour not_allowed)
				(footprints allowed)
			)
			(placement
				(enabled no)
				(sheetname "")
			)
			(fill
				(thermal_gap 0.5)
				(thermal_bridge_width 0.5)
				(island_removal_mode 0)
			)
			(polygon
				(pts
					(xy 421.894 -83.7565) (xy 422.402 -83.7565) (xy 422.402 -84.1375) (xy 421.894 -84.1375)
				)
			)
		)
	)
	(footprint ""
		(layer "F.Cu")
		(at 29.337 13.2715 -90)
		(property "Reference" "T1P35"
			(at 0 0 270)
			(layer "F.SilkS")
			(hide yes)
			(effects
				(font
					(size 1.27 1.27)
				)
			)
		)
		(property "Value" "*"
			(at 0 -3.44805 270)
			(unlocked yes)
			(layer "F.Fab")
			(hide yes)
			(effects
				(font
					(size 0.889 0.889)
					(thickness 0.1524)
				)
			)
		)
		(property "Device Type" "TPAD-SE-2P-GP_DISCRET-GA1-TPADA"
			(at 0 -4.97205 270)
			(unlocked yes)
			(layer "F.Fab")
			(hide yes)
			(effects
				(font
					(size 0.889 0.889)
					(thickness 0.1524)
				)
			)
		)
		(duplicate_pad_numbers_are_jumpers no)
		(fp_line
			(start -1.016 2.286)
			(end -1.016 -2.286)
			(stroke
				(width 0.1524)
				(type default)
			)
			(layer "F.SilkS")
		)
		(fp_line
			(start 1.016 2.286)
			(end -1.016 2.286)
			(stroke
				(width 0.1524)
				(type default)
			)
			(layer "F.SilkS")
		)
		(fp_line
			(start -1.016 -2.286)
			(end 1.016 -2.286)
			(stroke
				(width 0.1524)
				(type default)
			)
			(layer "F.SilkS")
		)
		(fp_line
			(start 1.016 -2.286)
			(end 1.016 2.286)
			(stroke
				(width 0.1524)
				(type default)
			)
			(layer "F.SilkS")
		)
		(fp_rect
			(start -1.27 2.54)
			(end 1.27 -2.54)
			(stroke
				(width 0)
				(type default)
			)
			(fill no)
			(layer "F.CrtYd")
		)
		(fp_rect
			(start -1.27 2.54)
			(end 1.27 -2.54)
			(stroke
				(width 0)
				(type default)
			)
			(fill no)
			(layer "F.Fab")
		)
		(pad "1" thru_hole circle
			(at 0 -1.27 270)
			(size 1.524 1.524)
			(drill 0.9144)
			(layers "*.Cu" "*.Mask")
			(remove_unused_layers no)
			(net "L12_50OHM_6INCH")
			(clearance -0.0508)
			(thermal_gap 0.127)
			(padstack
				(mode front_inner_back)
				(layer "Inner"
					(shape circle)
					(size 1.1684 1.1684)
					(clearance 0.127)
				)
				(layer "B.Cu"
					(shape circle)
					(size 1.524 1.524)
					(clearance -0.0508)
				)
			)
		)
		(pad "GND1" thru_hole rect
			(at 0 1.27 270)
			(size 1.524 1.524)
			(drill 0.9144)
			(layers "*.Cu" "*.Mask")
			(remove_unused_layers no)
			(net "GND")
			(clearance -0.0508)
			(thermal_gap 0.127)
			(padstack
				(mode front_inner_back)
				(layer "Inner"
					(shape circle)
					(size 1.1684 1.1684)
					(clearance 0.127)
				)
				(layer "B.Cu"
					(shape rect)
					(size 1.524 1.524)
					(clearance -0.0508)
				)
			)
		)
	)
	(footprint ""
		(layer "F.Cu")
		(at 451.85838 -35.8775 90)
		(property "Reference" "R25W29"
			(at 0 0 90)
			(layer "F.SilkS")
			(hide yes)
			(effects
				(font
					(size 1.27 1.27)
				)
			)
		)
		(property "Value" "*"
			(at 0.064008 -4.108196 90)
			(unlocked yes)
			(layer "F.Fab")
			(hide yes)
			(effects
				(font
					(size 1.27 1.016)
					(thickness 0.1524)
				)
			)
		)
		(property "Device Type" "120R2F-GP_RCL_GP-120R2F-GP,64.A"
			(at 0.064008 -5.632196 90)
			(unlocked yes)
			(layer "F.Fab")
			(hide yes)
			(effects
				(font
					(size 1.27 1.016)
					(thickness 0.1524)
				)
			)
		)
		(duplicate_pad_numbers_are_jumpers no)
		(fp_line
			(start 0.508 -0.9398)
			(end -0.508 -0.9398)
			(stroke
				(width 0.1524)
				(type default)
			)
			(layer "F.SilkS")
		)
		(fp_line
			(start -0.508 -0.9398)
			(end -0.508 0.9398)
			(stroke
				(width 0.1524)
				(type default)
			)
			(layer "F.SilkS")
		)
		(fp_rect
			(start -0.508 0.9398)
			(end 0.508 -0.9398)
			(stroke
				(width 0)
				(type default)
			)
			(fill no)
			(layer "F.CrtYd")
		)
		(fp_rect
			(start -0.508 0.9398)
			(end 0.508 -0.9398)
			(stroke
				(width 0)
				(type default)
			)
			(fill no)
			(layer "F.Fab")
		)
		(pad "1" smd custom
			(at 0 -0.4445 90)
			(size 0.1397 0.1397)
			(layers "F.Cu" "F.Mask" "F.Paste")
			(net "BMC_M_RST_N")
			(options
				(clearance outline)
				(anchor circle)
			)
			(primitives
				(gr_poly
					(pts
						(arc
							(start -0.1778 -0.2794)
							(mid -0.249642 -0.249642)
							(end -0.2794 -0.1778)
						)
						(arc
							(start -0.2794 0.1778)
							(mid -0.249642 0.249642)
							(end -0.1778 0.2794)
						)
						(arc
							(start 0.1778 0.2794)
							(mid 0.249642 0.249642)
							(end 0.2794 0.1778)
						)
						(arc
							(start 0.2794 -0.1778)
							(mid 0.249642 -0.249642)
							(end 0.1778 -0.2794)
						)
					)
					(width 0)
					(fill yes)
				)
			)
		)
		(pad "2" smd custom
			(at 0 0.4445 90)
			(size 0.1397 0.1397)
			(layers "F.Cu" "F.Mask" "F.Paste")
			(net "P1V2_AUX_BMC")
			(options
				(clearance outline)
				(anchor circle)
			)
			(primitives
				(gr_poly
					(pts
						(arc
							(start -0.1778 -0.2794)
							(mid -0.249642 -0.249642)
							(end -0.2794 -0.1778)
						)
						(arc
							(start -0.2794 0.1778)
							(mid -0.249642 0.249642)
							(end -0.1778 0.2794)
						)
						(arc
							(start 0.1778 0.2794)
							(mid 0.249642 0.249642)
							(end 0.2794 0.1778)
						)
						(arc
							(start 0.2794 -0.1778)
							(mid 0.249642 -0.249642)
							(end 0.1778 -0.2794)
						)
					)
					(width 0)
					(fill yes)
				)
			)
		)
	)
)
